(kicad_pcb
	(version 20240108)
	(generator "pcbnew")
	(generator_version "8.0")
	(general
		(thickness 1.62)
		(legacy_teardrops no)
	)
	(paper "A4")
	(title_block
		(title "Jetson Orin Baseboard")
		(date "2025-03-12")
		(rev "1.3.4")
		(company "Antmicro Ltd")
		(comment 1 "www.antmicro.com")
		(comment 9 "footprints 459-464 of 677")
	)
	(layers
		(0 "F.Cu" signal)
		(1 "In1.Cu" signal)
		(2 "In2.Cu" signal)
		(3 "In3.Cu" signal)
		(4 "In4.Cu" jumper)
		(5 "In5.Cu" signal)
		(6 "In6.Cu" signal)
		(31 "B.Cu" signal)
		(32 "B.Adhes" user "B.Adhesive")
		(33 "F.Adhes" user "F.Adhesive")
		(34 "B.Paste" user)
		(35 "F.Paste" user)
		(36 "B.SilkS" user "B.Silkscreen")
		(37 "F.SilkS" user "F.Silkscreen")
		(38 "B.Mask" user)
		(39 "F.Mask" user)
		(40 "Dwgs.User" user "User.Drawings")
		(41 "Cmts.User" user "User.Comments")
		(42 "Eco1.User" user "User.Eco1")
		(43 "Eco2.User" user "User.Eco2")
		(44 "Edge.Cuts" user)
		(45 "Margin" user)
		(46 "B.CrtYd" user "B.Courtyard")
		(47 "F.CrtYd" user "F.Courtyard")
		(48 "B.Fab" user)
		(49 "F.Fab" user)
	)
	(footprint "antmicro-footprints:C_0402_1005Metric"
		(layer "B.Cu")
		(at 61.4 109.2 -90)
		(descr "Capacitor SMD 0402")
		(tags "capacitor SMD 0402")
		(property "Reference" "C53"
			(at 1.05 -0.29 90)
			(layer "B.SilkS")
			(effects
				(font
					(size 0.7 0.7)
					(thickness 0.15)
				)
				(justify left bottom mirror)
			)
		)
		(property "Value" "C_100n_0402"
			(at 0 -1.4 90)
			(layer "B.Fab")
			(effects
				(font
					(size 0.7 0.7)
					(thickness 0.15)
				)
				(justify left bottom mirror)
			)
		)
		(property "Footprint" "antmicro-footprints:C_0402_1005Metric"
			(at 0 0 -90)
			(layer "F.Fab")
			(hide yes)
			(effects
				(font
					(size 1.27 1.27)
					(thickness 0.15)
				)
			)
		)
		(property "Datasheet" "https://www.murata.com/products/productdetail?partno=GRM155R61H104KE14%23"
			(at 0 0 -90)
			(layer "F.Fab")
			(hide yes)
			(effects
				(font
					(size 1.27 1.27)
					(thickness 0.15)
				)
			)
		)
		(property "Author" "Antmicro"
			(at -47.8 170.6 0)
			(layer "B.Fab")
			(hide yes)
			(effects
				(font
					(size 1 1)
					(thickness 0.15)
				)
				(justify mirror)
			)
		)
		(property "Dielectric" "X5R"
			(at -47.8 170.6 0)
			(layer "B.Fab")
			(hide yes)
			(effects
				(font
					(size 1 1)
					(thickness 0.15)
				)
				(justify mirror)
			)
		)
		(property "License" "Apache-2.0"
			(at -47.8 170.6 0)
			(layer "B.Fab")
			(hide yes)
			(effects
				(font
					(size 1 1)
					(thickness 0.15)
				)
				(justify mirror)
			)
		)
		(property "MPN" "GRM155R61H104KE14D"
			(at -47.8 170.6 0)
			(layer "B.Fab")
			(hide yes)
			(effects
				(font
					(size 1 1)
					(thickness 0.15)
				)
				(justify mirror)
			)
		)
		(property "Manufacturer" "Murata"
			(at -47.8 170.6 0)
			(layer "B.Fab")
			(hide yes)
			(effects
				(font
					(size 1 1)
					(thickness 0.15)
				)
				(justify mirror)
			)
		)
		(property "Val" "100n"
			(at -47.8 170.6 0)
			(layer "B.Fab")
			(hide yes)
			(effects
				(font
					(size 1 1)
					(thickness 0.15)
				)
				(justify mirror)
			)
		)
		(property "Voltage" "50V"
			(at -47.8 170.6 0)
			(layer "B.Fab")
			(hide yes)
			(effects
				(font
					(size 1 1)
					(thickness 0.15)
				)
				(justify mirror)
			)
		)
		(sheetname "USB Debug, DP")
		(sheetfile "usb.kicad_sch")
		(attr smd)
		(fp_rect
			(start -0.925 0.47)
			(end 0.925 -0.47)
			(stroke
				(width 0.05)
				(type default)
			)
			(fill none)
			(layer "B.CrtYd")
		)
		(fp_line
			(start -0.494 0.25)
			(end -0.494 -0.248)
			(stroke
				(width 0.15)
				(type solid)
			)
			(layer "B.Fab")
		)
		(fp_line
			(start 0.504 0.25)
			(end -0.494 0.25)
			(stroke
				(width 0.15)
				(type solid)
			)
			(layer "B.Fab")
		)
		(fp_line
			(start -0.494 -0.248)
			(end 0.504 -0.248)
			(stroke
				(width 0.15)
				(type solid)
			)
			(layer "B.Fab")
		)
		(fp_line
			(start 0.504 -0.248)
			(end 0.504 0.25)
			(stroke
				(width 0.15)
				(type solid)
			)
			(layer "B.Fab")
		)
		(fp_text user "${REFERENCE}"
			(at -0.932 -3.168 90)
			(layer "B.Fab")
			(hide yes)
			(effects
				(font
					(size 0.7 0.7)
					(thickness 0.15)
				)
				(justify left bottom mirror)
			)
		)
		(fp_text user "Author: Antmicro"
			(at -0.932 -4.17 90)
			(layer "B.Fab")
			(hide yes)
			(effects
				(font
					(size 0.7 0.7)
					(thickness 0.15)
				)
				(justify left bottom mirror)
			)
		)
		(fp_text user "License: Apache-2.0"
			(at -0.932 -5.17 90)
			(layer "B.Fab")
			(hide yes)
			(effects
				(font
					(size 0.7 0.7)
					(thickness 0.15)
				)
				(justify left bottom mirror)
			)
		)
		(pad "1" smd roundrect
			(at -0.48 0 270)
			(size 0.59 0.64)
			(layers "B.Cu" "B.Paste" "B.Mask")
			(roundrect_rratio 0.25)
			(net 480 "USBPD1_HV")
			(pintype "passive")
		)
		(pad "2" smd roundrect
			(at 0.48 0 270)
			(size 0.59 0.64)
			(layers "B.Cu" "B.Paste" "B.Mask")
			(roundrect_rratio 0.25)
			(net 1 "GND")
			(pintype "passive")
		)
	)
	(footprint "antmicro-footprints:R_0402_1005Metric"
		(layer "B.Cu")
		(at 98.4 84.25 180)
		(descr "Resistor SMD 0402")
		(tags "resistor SMD 0402")
		(property "Reference" "R9"
			(at -0.87 -1.33 0)
			(layer "B.SilkS")
			(effects
				(font
					(size 0.7 0.7)
					(thickness 0.15)
				)
				(justify left bottom mirror)
			)
		)
		(property "Value" "R_4k7_0402"
			(at 0 -1.4 0)
			(layer "B.Fab")
			(effects
				(font
					(size 0.7 0.7)
					(thickness 0.15)
				)
				(justify left bottom mirror)
			)
		)
		(property "Footprint" "antmicro-footprints:R_0402_1005Metric"
			(at 0 0 180)
			(layer "F.Fab")
			(hide yes)
			(effects
				(font
					(size 1.27 1.27)
					(thickness 0.15)
				)
			)
		)
		(property "Datasheet" "https://www.bourns.com/docs/product-datasheets/cr.pdf"
			(at 0 0 180)
			(layer "F.Fab")
			(hide yes)
			(effects
				(font
					(size 1.27 1.27)
					(thickness 0.15)
				)
			)
		)
		(property "Author" "Antmicro"
			(at 196.8 168.5 0)
			(layer "B.Fab")
			(hide yes)
			(effects
				(font
					(size 1 1)
					(thickness 0.15)
				)
				(justify mirror)
			)
		)
		(property "License" "Apache-2.0"
			(at 196.8 168.5 0)
			(layer "B.Fab")
			(hide yes)
			(effects
				(font
					(size 1 1)
					(thickness 0.15)
				)
				(justify mirror)
			)
		)
		(property "MPN" "CR0402-FX-4701GLF"
			(at 196.8 168.5 0)
			(layer "B.Fab")
			(hide yes)
			(effects
				(font
					(size 1 1)
					(thickness 0.15)
				)
				(justify mirror)
			)
		)
		(property "Manufacturer" "Bourns"
			(at 196.8 168.5 0)
			(layer "B.Fab")
			(hide yes)
			(effects
				(font
					(size 1 1)
					(thickness 0.15)
				)
				(justify mirror)
			)
		)
		(property "Tolerance" "1%"
			(at 196.8 168.5 0)
			(layer "B.Fab")
			(hide yes)
			(effects
				(font
					(size 1 1)
					(thickness 0.15)
				)
				(justify mirror)
			)
		)
		(property "Val" "4k7"
			(at 196.8 168.5 0)
			(layer "B.Fab")
			(hide yes)
			(effects
				(font
					(size 1 1)
					(thickness 0.15)
				)
				(justify mirror)
			)
		)
		(sheetname "CSI")
		(sheetfile "csi.kicad_sch")
		(attr smd)
		(fp_rect
			(start -0.925 0.47)
			(end 0.925 -0.47)
			(stroke
				(width 0.05)
				(type default)
			)
			(fill none)
			(layer "B.CrtYd")
		)
		(fp_rect
			(start -0.5 0.25)
			(end 0.5 -0.25)
			(stroke
				(width 0.15)
				(type solid)
			)
			(fill none)
			(layer "B.Fab")
		)
		(fp_text user "License: Apache-2.0"
			(at -0.95 -5.169 0)
			(layer "B.Fab")
			(hide yes)
			(effects
				(font
					(size 0.7 0.7)
					(thickness 0.15)
				)
				(justify left bottom mirror)
			)
		)
		(fp_text user "${REFERENCE}"
			(at -0.95 -3.168 0)
			(layer "B.Fab")
			(hide yes)
			(effects
				(font
					(size 0.7 0.7)
					(thickness 0.15)
				)
				(justify left bottom mirror)
			)
		)
		(fp_text user "Author: Antmicro"
			(at -0.95 -4.169 0)
			(layer "B.Fab")
			(hide yes)
			(effects
				(font
					(size 0.7 0.7)
					(thickness 0.15)
				)
				(justify left bottom mirror)
			)
		)
		(pad "1" smd roundrect
			(at -0.48 0 180)
			(size 0.59 0.64)
			(layers "B.Cu" "B.Paste" "B.Mask")
			(roundrect_rratio 0.25)
			(net 1 "GND")
			(pintype "passive")
		)
		(pad "2" smd roundrect
			(at 0.48 0 180)
			(size 0.59 0.64)
			(layers "B.Cu" "B.Paste" "B.Mask")
			(roundrect_rratio 0.25)
			(net 343 "/CSI/CSIB_5V_ISET")
			(pintype "passive")
		)
	)
	(footprint "antmicro-footprints:TP_SMD_0.75mm"
		(layer "B.Cu")
		(at 130.085 88.869999)
		(property "Reference" "TP12"
			(at 0.395 0.365001 0)
			(layer "B.SilkS")
			(effects
				(font
					(size 0.7 0.7)
					(thickness 0.15)
				)
				(justify right bottom mirror)
			)
		)
		(property "Value" "TP_0.75mm_SMD"
			(at 0 -1.2 0)
			(layer "B.Fab")
			(effects
				(font
					(size 0.7 0.7)
					(thickness 0.15)
				)
				(justify right bottom mirror)
			)
		)
		(property "Footprint" "antmicro-footprints:TP_SMD_0.75mm"
			(at 0 0 0)
			(layer "F.Fab")
			(hide yes)
			(effects
				(font
					(size 1.27 1.27)
					(thickness 0.15)
				)
			)
		)
		(property "Author" "Antmicro"
			(at 0 0 0)
			(layer "B.Fab")
			(hide yes)
			(effects
				(font
					(size 1 1)
					(thickness 0.15)
				)
				(justify mirror)
			)
		)
		(property "License" "Apache-2.0"
			(at 0 0 0)
			(layer "B.Fab")
			(hide yes)
			(effects
				(font
					(size 1 1)
					(thickness 0.15)
				)
				(justify mirror)
			)
		)
		(property "MPN" ""
			(at 0 0 0)
			(layer "B.Fab")
			(hide yes)
			(effects
				(font
					(size 1 1)
					(thickness 0.15)
				)
				(justify mirror)
			)
		)
		(property "Manufacturer" ""
			(at 0 0 0)
			(layer "B.Fab")
			(hide yes)
			(effects
				(font
					(size 1 1)
					(thickness 0.15)
				)
				(justify mirror)
			)
		)
		(sheetname "M.2")
		(sheetfile "m-2.kicad_sch")
		(attr exclude_from_pos_files exclude_from_bom)
		(fp_circle
			(center 0 0)
			(end 0.475 0)
			(stroke
				(width 0.05)
				(type default)
			)
			(fill none)
			(layer "B.CrtYd")
		)
		(fp_text user "License: Apache-2.0"
			(at -0.4 -5.101 0)
			(layer "B.Fab")
			(hide yes)
			(effects
				(font
					(size 0.7 0.7)
					(thickness 0.15)
				)
				(justify right bottom mirror)
			)
		)
		(fp_text user "${REFERENCE}"
			(at -0.4 -2.7 0)
			(layer "B.Fab")
			(hide yes)
			(effects
				(font
					(size 0.7 0.7)
					(thickness 0.15)
				)
				(justify right bottom mirror)
			)
		)
		(fp_text user "Author: Antmicro"
			(at -0.4 -3.901 0)
			(layer "B.Fab")
			(hide yes)
			(effects
				(font
					(size 0.7 0.7)
					(thickness 0.15)
				)
				(justify right bottom mirror)
			)
		)
		(pad "1" smd circle
			(at 0 0)
			(size 0.75 0.75)
			(layers "B.Cu" "B.Mask")
			(net 244 "/M.2/M2_M_SMB_CLK")
			(pinfunction "1")
			(pintype "passive")
		)
	)
	(footprint "antmicro-footprints:C_0402_1005Metric"
		(layer "B.Cu")
		(at 97.45 93.45)
		(descr "Capacitor SMD 0402")
		(tags "capacitor SMD 0402")
		(property "Reference" "C88"
			(at 3.26 0.32 180)
			(layer "B.SilkS")
			(effects
				(font
					(size 0.7 0.7)
					(thickness 0.15)
				)
				(justify left bottom mirror)
			)
		)
		(property "Value" "C_100n_0402"
			(at 0 -1.4 180)
			(layer "B.Fab")
			(effects
				(font
					(size 0.7 0.7)
					(thickness 0.15)
				)
				(justify left bottom mirror)
			)
		)
		(property "Footprint" "antmicro-footprints:C_0402_1005Metric"
			(at 0 0 0)
			(layer "F.Fab")
			(hide yes)
			(effects
				(font
					(size 1.27 1.27)
					(thickness 0.15)
				)
			)
		)
		(property "Datasheet" "https://www.murata.com/products/productdetail?partno=GRM155R61H104KE14%23"
			(at 0 0 0)
			(layer "F.Fab")
			(hide yes)
			(effects
				(font
					(size 1.27 1.27)
					(thickness 0.15)
				)
			)
		)
		(property "Author" "Antmicro"
			(at 0 0 0)
			(layer "B.Fab")
			(hide yes)
			(effects
				(font
					(size 1 1)
					(thickness 0.15)
				)
				(justify mirror)
			)
		)
		(property "Dielectric" "X5R"
			(at 0 0 0)
			(layer "B.Fab")
			(hide yes)
			(effects
				(font
					(size 1 1)
					(thickness 0.15)
				)
				(justify mirror)
			)
		)
		(property "License" "Apache-2.0"
			(at 0 0 0)
			(layer "B.Fab")
			(hide yes)
			(effects
				(font
					(size 1 1)
					(thickness 0.15)
				)
				(justify mirror)
			)
		)
		(property "MPN" "GRM155R61H104KE14D"
			(at 0 0 0)
			(layer "B.Fab")
			(hide yes)
			(effects
				(font
					(size 1 1)
					(thickness 0.15)
				)
				(justify mirror)
			)
		)
		(property "Manufacturer" "Murata"
			(at 0 0 0)
			(layer "B.Fab")
			(hide yes)
			(effects
				(font
					(size 1 1)
					(thickness 0.15)
				)
				(justify mirror)
			)
		)
		(property "Val" "100n"
			(at 0 0 0)
			(layer "B.Fab")
			(hide yes)
			(effects
				(font
					(size 1 1)
					(thickness 0.15)
				)
				(justify mirror)
			)
		)
		(property "Voltage" "50V"
			(at 0 0 0)
			(layer "B.Fab")
			(hide yes)
			(effects
				(font
					(size 1 1)
					(thickness 0.15)
				)
				(justify mirror)
			)
		)
		(sheetname "HDMI")
		(sheetfile "hdmi.kicad_sch")
		(attr smd)
		(fp_rect
			(start -0.925 0.47)
			(end 0.925 -0.47)
			(stroke
				(width 0.05)
				(type default)
			)
			(fill none)
			(layer "B.CrtYd")
		)
		(fp_line
			(start -0.494 -0.248)
			(end 0.504 -0.248)
			(stroke
				(width 0.15)
				(type solid)
			)
			(layer "B.Fab")
		)
		(fp_line
			(start -0.494 0.25)
			(end -0.494 -0.248)
			(stroke
				(width 0.15)
				(type solid)
			)
			(layer "B.Fab")
		)
		(fp_line
			(start 0.504 -0.248)
			(end 0.504 0.25)
			(stroke
				(width 0.15)
				(type solid)
			)
			(layer "B.Fab")
		)
		(fp_line
			(start 0.504 0.25)
			(end -0.494 0.25)
			(stroke
				(width 0.15)
				(type solid)
			)
			(layer "B.Fab")
		)
		(fp_text user "${REFERENCE}"
			(at -0.932 -3.168 180)
			(layer "B.Fab")
			(hide yes)
			(effects
				(font
					(size 0.7 0.7)
					(thickness 0.15)
				)
				(justify left bottom mirror)
			)
		)
		(fp_text user "License: Apache-2.0"
			(at -0.932 -5.17 180)
			(layer "B.Fab")
			(hide yes)
			(effects
				(font
					(size 0.7 0.7)
					(thickness 0.15)
				)
				(justify left bottom mirror)
			)
		)
		(fp_text user "Author: Antmicro"
			(at -0.932 -4.17 180)
			(layer "B.Fab")
			(hide yes)
			(effects
				(font
					(size 0.7 0.7)
					(thickness 0.15)
				)
				(justify left bottom mirror)
			)
		)
		(pad "1" smd roundrect
			(at -0.48 0)
			(size 0.59 0.64)
			(layers "B.Cu" "B.Paste" "B.Mask")
			(roundrect_rratio 0.25)
			(net 664 "/HDMI/DP_MUX_D2-")
			(pintype "passive")
		)
		(pad "2" smd roundrect
			(at 0.48 0)
			(size 0.59 0.64)
			(layers "B.Cu" "B.Paste" "B.Mask")
			(roundrect_rratio 0.25)
			(net 375 "DP1_TXD1_HDMI_TX1_N")
			(pintype "passive")
		)
	)
	(footprint "antmicro-footprints:R_0402_1005Metric"
		(layer "B.Cu")
		(at 68.1 83.3 180)
		(descr "Resistor SMD 0402")
		(tags "resistor SMD 0402")
		(property "Reference" "R80"
			(at -1.06 -1.3 0)
			(layer "B.SilkS")
			(effects
				(font
					(size 0.7 0.7)
					(thickness 0.15)
				)
				(justify left bottom mirror)
			)
		)
		(property "Value" "R_4k7_0402"
			(at 0 -1.4 0)
			(layer "B.Fab")
			(effects
				(font
					(size 0.7 0.7)
					(thickness 0.15)
				)
				(justify left bottom mirror)
			)
		)
		(property "Footprint" "antmicro-footprints:R_0402_1005Metric"
			(at 0 0 180)
			(layer "F.Fab")
			(hide yes)
			(effects
				(font
					(size 1.27 1.27)
					(thickness 0.15)
				)
			)
		)
		(property "Datasheet" "https://www.bourns.com/docs/product-datasheets/cr.pdf"
			(at 0 0 180)
			(layer "F.Fab")
			(hide yes)
			(effects
				(font
					(size 1.27 1.27)
					(thickness 0.15)
				)
			)
		)
		(property "Author" "Antmicro"
			(at 136.2 166.6 0)
			(layer "B.Fab")
			(hide yes)
			(effects
				(font
					(size 1 1)
					(thickness 0.15)
				)
				(justify mirror)
			)
		)
		(property "License" "Apache-2.0"
			(at 136.2 166.6 0)
			(layer "B.Fab")
			(hide yes)
			(effects
				(font
					(size 1 1)
					(thickness 0.15)
				)
				(justify mirror)
			)
		)
		(property "MPN" "CR0402-FX-4701GLF"
			(at 136.2 166.6 0)
			(layer "B.Fab")
			(hide yes)
			(effects
				(font
					(size 1 1)
					(thickness 0.15)
				)
				(justify mirror)
			)
		)
		(property "Manufacturer" "Bourns"
			(at 136.2 166.6 0)
			(layer "B.Fab")
			(hide yes)
			(effects
				(font
					(size 1 1)
					(thickness 0.15)
				)
				(justify mirror)
			)
		)
		(property "Tolerance" "1%"
			(at 136.2 166.6 0)
			(layer "B.Fab")
			(hide yes)
			(effects
				(font
					(size 1 1)
					(thickness 0.15)
				)
				(justify mirror)
			)
		)
		(property "Val" "4k7"
			(at 136.2 166.6 0)
			(layer "B.Fab")
			(hide yes)
			(effects
				(font
					(size 1 1)
					(thickness 0.15)
				)
				(justify mirror)
			)
		)
		(sheetname "SoM")
		(sheetfile "som.kicad_sch")
		(attr smd)
		(fp_rect
			(start -0.925 0.47)
			(end 0.925 -0.47)
			(stroke
				(width 0.05)
				(type default)
			)
			(fill none)
			(layer "B.CrtYd")
		)
		(fp_rect
			(start -0.5 0.25)
			(end 0.5 -0.25)
			(stroke
				(width 0.15)
				(type solid)
			)
			(fill none)
			(layer "B.Fab")
		)
		(fp_text user "Author: Antmicro"
			(at -0.95 -4.169 0)
			(layer "B.Fab")
			(hide yes)
			(effects
				(font
					(size 0.7 0.7)
					(thickness 0.15)
				)
				(justify left bottom mirror)
			)
		)
		(fp_text user "${REFERENCE}"
			(at -0.95 -3.168 0)
			(layer "B.Fab")
			(hide yes)
			(effects
				(font
					(size 0.7 0.7)
					(thickness 0.15)
				)
				(justify left bottom mirror)
			)
		)
		(fp_text user "License: Apache-2.0"
			(at -0.95 -5.169 0)
			(layer "B.Fab")
			(hide yes)
			(effects
				(font
					(size 0.7 0.7)
					(thickness 0.15)
				)
				(justify left bottom mirror)
			)
		)
		(pad "1" smd roundrect
			(at -0.48 0 180)
			(size 0.59 0.64)
			(layers "B.Cu" "B.Paste" "B.Mask")
			(roundrect_rratio 0.25)
			(net 714 "GPIO010")
			(pintype "passive")
		)
		(pad "2" smd roundrect
			(at 0.48 0 180)
			(size 0.59 0.64)
			(layers "B.Cu" "B.Paste" "B.Mask")
			(roundrect_rratio 0.25)
			(net 112 "+1V8")
			(pintype "passive")
		)
	)
	(footprint "antmicro-footprints:TP_SMD_0.75mm"
		(layer "B.Cu")
		(at 68.165 121.57 180)
		(property "Reference" "TP53"
			(at 1.49 -1.53 0)
			(layer "B.SilkS")
			(hide yes)
			(effects
				(font
					(size 0.7 0.7)
					(thickness 0.15)
				)
				(justify left bottom mirror)
			)
		)
		(property "Value" "TP_0.75mm_SMD"
			(at 0 -1.2 0)
			(layer "B.Fab")
			(effects
				(font
					(size 0.7 0.7)
					(thickness 0.15)
				)
				(justify left bottom mirror)
			)
		)
		(property "Footprint" "antmicro-footprints:TP_SMD_0.75mm"
			(at 0 0 180)
			(layer "F.Fab")
			(hide yes)
			(effects
				(font
					(size 1.27 1.27)
					(thickness 0.15)
				)
			)
		)
		(property "Author" "Antmicro"
			(at 136.33 243.14 0)
			(layer "B.Fab")
			(hide yes)
			(effects
				(font
					(size 1 1)
					(thickness 0.15)
				)
				(justify mirror)
			)
		)
		(property "License" "Apache-2.0"
			(at 136.33 243.14 0)
			(layer "B.Fab")
			(hide yes)
			(effects
				(font
					(size 1 1)
					(thickness 0.15)
				)
				(justify mirror)
			)
		)
		(property "MPN" ""
			(at 136.33 243.14 0)
			(layer "B.Fab")
			(hide yes)
			(effects
				(font
					(size 1 1)
					(thickness 0.15)
				)
				(justify mirror)
			)
		)
		(property "Manufacturer" ""
			(at 136.33 243.14 0)
			(layer "B.Fab")
			(hide yes)
			(effects
				(font
					(size 1 1)
					(thickness 0.15)
				)
				(justify mirror)
			)
		)
		(sheetname "Supply")
		(sheetfile "supply.kicad_sch")
		(attr exclude_from_pos_files exclude_from_bom)
		(fp_circle
			(center 0 0)
			(end 0.475 0)
			(stroke
				(width 0.05)
				(type default)
			)
			(fill none)
			(layer "B.CrtYd")
		)
		(fp_text user "${REFERENCE}"
			(at -0.4 -2.7 0)
			(layer "B.Fab")
			(hide yes)
			(effects
				(font
					(size 0.7 0.7)
					(thickness 0.15)
				)
				(justify left bottom mirror)
			)
		)
		(fp_text user "Author: Antmicro"
			(at -0.4 -3.901 0)
			(layer "B.Fab")
			(hide yes)
			(effects
				(font
					(size 0.7 0.7)
					(thickness 0.15)
				)
				(justify left bottom mirror)
			)
		)
		(fp_text user "License: Apache-2.0"
			(at -0.4 -5.101 0)
			(layer "B.Fab")
			(hide yes)
			(effects
				(font
					(size 0.7 0.7)
					(thickness 0.15)
				)
				(justify left bottom mirror)
			)
		)
		(pad "1" smd circle
			(at 0 0 180)
			(size 0.75 0.75)
			(layers "B.Cu" "B.Mask")
			(net 99 "+5V")
			(pinfunction "1")
			(pintype "passive")
		)
	)
)
